# S9S_MB_2U (Grand Teton) — schematic parts with pin connectivity, parts 6005–6046 of 6093; source: Cadence DE-HDL packaged netlist (pstxprt.dat, pstxnet.dat, pstchip.dat)

U301  GTL2014PW  IC  pkg TSSOP14  page 226
  1  DIR  IN  = PD_CPU0_ERRS_DIR
  2  B0  BI  = H_CPU_CATERR_LVC1_R_N
  3  B1  BI  = H_CPU_CATERR_LVC1_R_N
  4  VREF  POWER  = P0V62_CPU0_ERRS_VREF
  5  B2  BI  = H_CPU_RMCA_LVC1_R_N
  6  B3  BI  = PWRGD_CPUPWRGD_LVC1
  7  GND_0  POWER  = GND
  8  GND_1  POWER  = GND
  9  A3  BI  = PWRGD_CPUPWRGD_LVC2_R
  10  A2  BI  = H_CPU_RMCA_LVC2_R1_N
  11  GND_2  POWER  = GND
  12  A1  BI  = H_CPU_CATERR_LVC2_R1_N
  13  A0  BI  = H_CPU_CATERR_LVC2_BMC_R_N
  14  VCC  POWER  = P3V3

U304  GTL2014PW  IC  pkg TSSOP14  page 225
  1  DIR  IN  = PD_GTL2014_BMC_JTAG_DIR_0
  2  B0  BI  = RST_CPU0_DRAM_GH_PLD_N
  3  B1  BI  = RST_CPU0_DRAM_EF_PLD_N
  4  VREF  POWER  = P0V62_CPU0_RST_DDR_VREF
  5  B2  BI  = RST_CPU0_DRAM_CD_PLD_N
  6  B3  BI  = RST_CPU0_DRAM_AB_PLD_N
  7  GND_0  POWER  = GND
  8  GND_1  POWER  = GND
  9  A3  BI  = RST_CPU0_DRAM_AB_PLD_LVT3_R_N
  10  A2  BI  = RST_CPU0_DRAM_CD_PLD_LVT3_R_N
  11  GND_2  POWER  = GND
  12  A1  BI  = RST_CPU0_DRAM_EF_PLD_LVT3_R_N
  13  A0  BI  = RST_CPU0_DRAM_GH_PLD_LVT3_R_N
  14  VCC  POWER  = P3V3_AUX

U305  GTL2014PW  IC  pkg TSSOP14  page 225
  1  DIR  IN  = PD_GTL2014_BMC_JTAG_DIR_1
  2  B0  BI  = RST_CPU1_DRAM_GH_PLD_N
  3  B1  BI  = RST_CPU1_DRAM_EF_PLD_N
  4  VREF  POWER  = P0V62_CPU1_RST_DDR_VREF
  5  B2  BI  = RST_CPU1_DRAM_CD_PLD_N
  6  B3  BI  = RST_CPU1_DRAM_AB_PLD_N
  7  GND_0  POWER  = GND
  8  GND_1  POWER  = GND
  9  A3  BI  = RST_CPU1_DRAM_AB_PLD_LVT3_R_N
  10  A2  BI  = RST_CPU1_DRAM_CD_PLD_LVT3_R_N
  11  GND_2  POWER  = GND
  12  A1  BI  = RST_CPU1_DRAM_EF_PLD_LVT3_R_N
  13  A0  BI  = RST_CPU1_DRAM_GH_PLD_LVT3_R_N
  14  VCC  POWER  = P3V3_AUX

U306  GTL2014PW  IC  pkg TSSOP14  page 225
  1  DIR  IN  = PD_CPU1_ERRS_U306_DIR
  2  B0  BI  = PD_GTL2014_ERROR_B0
  3  B1  BI  = H_CPU_ERR2_LVC1_N
  4  VREF  POWER  = P0V62_CPU0_ERRS_U306_VREF
  5  B2  BI  = H_CPU_ERR1_LVC1_N
  6  B3  BI  = H_CPU_ERR0_LVC1_N
  7  GND_0  POWER  = GND
  8  GND_1  POWER  = GND
  9  A3  BI  = H_CPU_ERR0_LVC2_R_N
  10  A2  BI  = H_CPU_ERR1_LVC2_R_N
  11  GND_2  POWER  = GND
  12  A1  BI  = H_CPU_ERR2_LVC2_R_N
  13  A0  BI  = NC_U306_A0
  14  VCC  POWER  = P3V3

U307  MOSFET_N  BSS138K IC  pkg SMLF  page 257
  D  DRAIN  OUT  = FM_LPC_ESPI_SEL
  G  GATE  IN  = FM_ESPI_PLD_R_EN_BUF_R
  S  SOURCE  BI  = GND

U308  74LVC2G07DW7  74LVC2G07DW-7 IC  pkg SOT363_0-65_2X1-25XC  page 246
  1  \1a\  IN  = PWRGD_P3V3_AUX_PDB_R
  2  GND  POWER  = GND
  3  \2a\  IN  = NC
  4  \2y\  OUT  = NC
  5  VCC  POWER  = P3V3_AUX
  6  \1y\  OUT  = PWRGD_P3V3_AUX_PDB_BUF_R

U309  PI3EQX1002EZREX  IC  pkg TQFN24_TH_0-35_2-5X2-5  page 169
  1  EQA  IN  = FM_USB3_1_EQA
  2  FGA  IN  = FM_USB3_1_FGA
  3  SWA  IN  = FM_USB3_1_SWA
  4  EN  IN  = FM_USB3_1_EN_N
  5  VDD_1  POWER  = P3V3_AUX_USB_BUF
  6  AIP  IN  = USB3_PCH_TX_C_DP<4>
  7  AIN  IN  = USB3_PCH_TX_C_DN<4>
  8  GND_1  POWER  = GND
  9  GND_2  POWER  = GND
  10  GND_3  POWER  = GND
  11  BON  OUT  = USB3_PCH_RX_BUF_C_DN<4>
  12  BOP  OUT  = USB3_PCH_RX_BUF_C_DP<4>
  13  RXDET_EN  IN  = FM_USB3_1_RXDET_EN
  14  SWB  IN  = FM_USB3_1_SWB
  15  FGB  IN  = FM_USB3_1_FGB
  16  EQB  IN  = FM_USB3_1_EQB
  17  VDD_2  POWER  = P3V3_AUX_USB_BUF
  18  BIP  IN  = USB3_PCH_RX_C_DP<4>
  19  BIN  IN  = USB3_PCH_RX_C_DN<4>
  20  GND_4  POWER  = GND
  21  GND_5  POWER  = GND
  22  GND_6  POWER  = GND
  23  AON  OUT  = USB3_PCH_TX_BUF_DN<4>
  24  AOP  OUT  = USB3_PCH_TX_BUF_DP<4>
  TH  TH_GND  POWER  = GND

U312  TUSB211IRWBR  EMPTY  pkg X2QFN12_0-4_1-6X1-6  page 196
  1  D1M  BI  = USB2_HUB_2_BUF_EXT_R_DN
  2  D1P  BI  = USB2_HUB_2_BUF_EXT_R_DP
  3  TEST  IN  = TP_USB_HUB_2_TEST
  4  CD  OUT  = TP_USB_HUB_2_CD
  5  RSTN  IN  = PD_USB_HUB_2_RSTN
  6  EQ  IN  = PD_USB_HUB_2_EQ
  7  D2P  BI  = USB2_HUB_2_BUF_EXT_R_DP
  8  D2M  BI  = USB2_HUB_2_BUF_EXT_R_DN
  9  ENA_HS  OUT  = TP_USB_HUB_2_ENA_HS
  10  GND  POWER  = GND
  11  VREG  OUT  = PD_USB_HUB_2_VREG
  12  VCC  POWER  = P3V3_AUX

U313  GL852GOHY60  GL852G-OHY60 EMPTY  pkg QFN28_THXL  page 196
  1  DM0  BI  = USB2_PCH_0_R_DN
  2  DP0  BI  = USB2_PCH_0_R_DP
  3  DM1  BI  = USB2_HUB_2_EXT_DN
  4  DP1  BI  = USB2_HUB_2_EXT_DP
  5  AVDD(0)  POWER  = P3V3_AUX_USB_HUB_2
  6  DM2  BI  = NC_USB_HUB_2_DM2
  7  DP2  BI  = NC_USB_HUB_2_DP2
  8  RREF  IN  = USB_HUB_2_RREF
  9  AVDD(1)  POWER  = P3V3_AUX_USB_HUB_2
  10  X1  IN  = USB_HUB_2_XTAL_IN
  11  X2  OUT  = USB_HUB_2_XTAL_OUT
  12  DM3  BI  = NC_USB_HUB_2_DM3
  13  DP3  BI  = NC_USB_HUB_2_DP3
  14  AVDD(2)  POWER  = P3V3_AUX_USB_HUB_2
  15  DM4  BI  = NC_USB_HUB_2_DM4
  16  DP4  BI  = NC_USB_HUB_2_DP4
  17  \reset#\  IN  = RST_USB_HUB_2_R_N
  18  \test||scl\  BI  = USB_HUB_2_TEST
  19  \ovcur4#\  IN  = USB_HUB_2_OVCUR4
  20  \ovcur3#\  IN  = USB_HUB_2_OVCUR3
  21  DVDD  POWER  = USB_HUB_2_DVDD
  22  PSELF  IN  = USB_HUB_2_PSELF
  23  PGANG  BI  = USB_HUB_2_PGANG
  24  \ovcur2#||smd\  BI  = USB_HUB_2_OVCUR2
  25  \ovcur1#||smc\  IN  = USB_HUB_2_OVCUR1
  26  SDA  BI  = NC_USB_HUB_2_SDA
  27  V5  POWER  = P3V3_AUX_USB_HUB_2
  28  V33  POWER  = P3V3_AUX_USB_HUB_2
  TH  TH  POWER  = GND

U314  9ZXL0451EKILFT  IC  pkg VFQFPN32_TH_0-5_5X5XD  page 211
  1  \^ckpwrgd_pd#\  IN  = FM_9ZXL045_DEV_EN
  2  VDDR  POWER  = P3V3_9ZXL045_VDDR
  3  DIF_IN  IN  = CLK_100M_GPU_SWB_REF_DP
  4  \dif_in#\  IN  = CLK_100M_GPU_SWB_REF_DN
  5  VSADR0_TRI  IN  = CLK_9ZXL045_SADR0
  6  SMBDAT  BI  = SMB_HOST_9ZXL045_3V3AUX_SDA
  7  SMBCLK  IN  = SMB_HOST_9ZXL045_3V3AUX_SCL
  8  \fbout_nc#\  OUT  = NC_U314_FBOUT_N
  9  FBOUT_NC  OUT  = NC_U314_FBOUT
  10  NC0  TRI  = NC_U314_NC0
  11  NC1  TRI  = NC_U314_NC1
  12  VDD0  POWER  = P3V3_9ZXL045_VDD
  13  DIF0  OUT  = CLK_100M_SWB_R_DP
  14  \dif0#\  OUT  = CLK_100M_SWB_R_DN
  15  \voe0#\  IN  = FM_9ZXL045_0_OE_N
  16  VDD1  POWER  = P3V3_9ZXL045_VDD
  17  NC2  TRI  = NC_U314_NC2
  18  \voe1#\  IN  = FM_9ZXL045_1_OE_N
  19  DIF1  OUT  = CLK_100M_GPU_1_R_DP
  20  \dif1#\  OUT  = CLK_100M_GPU_1_R_DN
  21  VDD2  POWER  = P3V3_9ZXL045_VDD
  22  DIF2  OUT  = CLK_100M_GPU_2_R_DP
  23  \dif2#\  OUT  = CLK_100M_GPU_2_R_DN
  24  \voe2#\  IN  = FM_9ZXL045_2_OE_N
  25  VDD3  POWER  = P3V3_9ZXL045_VDD
  26  \voe3#\  IN  = FM_9ZXL045_3_OE_N
  27  DIF3  OUT  = TP_CLK_100M_BUF_DIF3_DP
  28  \dif3#\  OUT  = TP_CLK_100M_BUF_DIF3_DN
  29  VDD4  POWER  = P3V3_9ZXL045_VDD
  30  NC3  TRI  = NC_U314_NC3
  31  VDDA  POWER  = P3V3_9ZXL045_VDDA
  32  \^hibw_bypm_lobw#\  IN  = CLK_9ZXL045_HIBW
  33  EPAD_GND  POWER  = GND

U315  PCA9617ADP  IC  pkg TSSOP8_3XB  page 237
  1  VCCA  POWER  = P3V3_AUX
  2  SCLA  BI  = SMB_HOST_CLK_BUF_3V3AUX_SCL
  3  SDAA  BI  = SMB_HOST_CLK_BUF_3V3AUX_SDA
  4  GND  POWER  = GND
  5  EN  IN  = PU_CLK_BUF_ISO_EN
  6  SDAB  BI  = SMB_HOST_CLK_BUF_ISO_3V3AUX_S_2
  7  SCLB  BI  = SMB_HOST_CLK_BUF_ISO_3V3AUX_S_1
  8  VCCB  POWER  = P3V3

U316  74LVC2G17GW  IC  pkg SOT363  page 145
  1  A0  IN  = SWB_HSC_EN
  2  GND  POWER  = GND
  3  A1  IN  = GND
  4  B1  OUT  = NC_U316_2Y
  5  VCC  POWER  = P3V3_AUX
  6  B0  OUT  = SWB_HSC_EN_BUF_R

U320  74LVC1G66GV  IC  pkg SC74AXA  page 155
  1  Y  BI  = CLK_50M_NCSI_OCP_SFF
  2  Z  BI  = CLK_50M_NCSI_OCP_SFF_ISO_R
  3  GND  POWER  = GND
  4  E  IN  = FB_BMC_ISOLATE
  5  VCC  POWER  = P3V3_AUX

U321  74LVC1G66GV  IC  pkg SC74AXA  page 161
  1  Y  BI  = CLK_50M_NCSI_OCP_V3_2
  2  Z  BI  = CLK_50M_NCSI_OCP_V3_2_ISO_R
  3  GND  POWER  = GND
  4  E  IN  = FB_BMC_ISOLATE1
  5  VCC  POWER  = P3V3_AUX

U322  74LVC1G08W57  74LVC1G08W5-7 IC  pkg SOT25-5_0-95_3X1-6  page 158
  1  A  IN  = HP_OCP_V3_1_RST_R
  2  B  IN  = HP_LVC3_OCP_V3_1_P12V_PWRGD
  3  GND  POWER  = GND
  4  Y  OUT  = HP_LVC3_OCP_V3_1_PWRGD
  5  VCC  POWER  = P3V3_AUX

U323  74LVC1G08W57  74LVC1G08W5-7 IC  pkg SOT25-5_0-95_3X1-6  page 164
  1  A  IN  = HP_OCP_V3_2_RST_R
  2  B  IN  = HP_LVC3_OCP_V3_2_P12V_PWRGD
  3  GND  POWER  = GND
  4  Y  OUT  = HP_LVC3_OCP_V3_2_PWRGD
  5  VCC  POWER  = P3V3_AUX

U324  MOSFET_NCH_GDS_ESD_PROTECTED  2N7002K IC  pkg SOT23_GDSXC  page 260
  D  D  BI  = VR_P5V_EN_D
  G  G  IN  = VR_P5V_EN_N
  S  S  BI  = GND

U325  MOSFET_N  BSS138K IC  pkg SMLF  page 306
  D  DRAIN  OUT  = IRQ_UV_DETECT_N
  G  GATE  IN  = A_P12V_STBY_FPH_GATE
  S  SOURCE  BI  = GND

U327  74CBTLV3126PW  IC  pkg TSSOP14  page 248
  1  \1oe\  IN  = JTAG_BMC_SW_R_OE
  2  \1a\  POWER  = JTAG_BMC_TCK_R
  3  \1b\  BI  = JTAG_BMC_SW_TCK_R
  4  \2oe\  OUT  = JTAG_BMC_SW_R_OE
  5  \2a\  BI  = JTAG_BMC_TMS_R
  6  \2b\  BI  = JTAG_BMC_SW_TMS_R
  7  GND  POWER  = GND
  8  \3b\  BI  = JTAG_BMC_SW_TDI_R
  9  \3a\  BI  = JTAG_BMC_TDI_R
  10  \3oe\  BI  = JTAG_BMC_SW_R_OE
  11  \4b\  BI  = JTAG_BMC_SW_TDO_R
  12  \4a\  BI  = JTAG_BMC_TDO_R
  13  \4oe\  BI  = JTAG_BMC_SW_R_OE
  14  VCC  BI  = P3V3_AUX

U328  DS125BR111RTWR  EMPTY  pkg WQFN24_TH_0-5_4X4XA  page 167
  1  \eqb0||ad3\  IN  = FM_P2E_BUF2_EQB0
  2  \eqb1||ad2\  IN  = FM_P2E_BUF2_EQB1
  3  ENSMB  IN  = PD_P2E_BUF2_ENSMB
  4  \sda||voda_db\  BI  = FM_P2E_BUF2_VODA_DB
  5  \scl||vodb_db\  BI  = FM_P2E_BUF2_VODB_DB
  6  PWDN  IN  = FM_P2E_EN2_N
  7  \outa+\  OUT  = P2E_MB_BMC_TX_BUF2_DP<0>
  8  \outa-\  OUT  = P2E_MB_BMC_TX_BUF2_DN<0>
  9  \eqa1||ad1\  IN  = FM_P2E_BUF2_EQA1
  10  \eqa0||ad0\  IN  = FM_P2E_BUF2_EQA0
  11  \inb+\  IN  = P2E_MB_BMC_RX_R2_DP<0>
  12  \inb-\  IN  = P2E_MB_BMC_RX_R2_DN<0>
  13  RES  IN  = NC_RES
  14  SD_TH  IN  = FM_P2E_BUF2_SD_TH
  15  VIN  POWER  = P3V3_AUX
  16  VDD_SEL  IN  = GND
  17  \vod_sel||readen#\  IN  = FM_P2E_BUF2_VOD_SEL
  18  \rxdet||done#\  BI  = FM_P2E_BUF2_RXDET
  19  \outb-\  OUT  = P2E_MB_BMC_RX_BUF2_C_DN<0>
  20  \outb+\  OUT  = P2E_MB_BMC_RX_BUF2_C_DP<0>
  21  VDD_21  POWER  = P2E_BUF2_VDD
  22  VDD_22  POWER  = P2E_BUF2_VDD
  23  \ina-\  IN  = P2E_MB_BMC_TX_C_R2_DN<0>
  24  \ina+\  IN  = P2E_MB_BMC_TX_C_R2_DP<0>
  25  TH_GND  POWER  = GND

U329  MOSFET_NCH_GDS_ESD_PROTECTED  2N7002K EMPTY  pkg SOT23_GDSXC  page 306
  D  D  BI  = A_HSC_LOW_DRAIN
  G  G  IN  = A_HSC_LOW_GATE
  S  S  BI  = GND

U330  APX80929SAG7  APX809-29SAG-7 IC  pkg SOT23_123XI  page 260
  1  GND  POWER  = GND
  2  RESET_L  OUT  = PWRGD_P3V3_R1
  3  VCC  POWER  = P3V3

U331  INA230AIRGTR  EMPTY  pkg QFN16_THXI  page 251
  1  A1  IN  = HSC_TYPE_ADC_A1
  2  A0  IN  = HSC_TYPE_ADC_A0
  3  ALERT  OUT  = TP_HSC_TYPE_ADC_ALERT
  4  SDA  BI  = SMB_HSC_TYPE_ADC_SDA
  5  SCL  IN  = SMB_HSC_TYPE_ADC_SCL
  6  NC0  OUT  = NC_HSC_TYPE_NC0
  7  NC1  OUT  = NC_HSC_TYPE_NC1
  8  NC2  OUT  = NC_HSC_TYPE_NC2
  9  VS  POWER  = P3V3_AUX
  10  GND  POWER  = GND
  11  \bus\  IN  = HSC_TYPE_ADC
  12  \in-\  IN  = NC_HSC_TYPE_VINM
  13  \in+\  IN  = NC_HSC_TYPE_VINP
  14  NC3  OUT  = NC_HSC_TYPE_NC3
  15  NC4  OUT  = NC_HSC_TYPE_NC4
  16  NC5  OUT  = NC_HSC_TYPE_NC5
  TH  TH  POWER  = GND

U332  74LVC2G07DW7  74LVC2G07DW-7 EMPTY  pkg SOT363_0-65_2X1-25XC  page 224
  1  \1a\  IN  = FM_AC_PWR_BTN_PLD_N
  2  GND  POWER  = GND
  3  \2a\  IN  = GND
  4  \2y\  OUT  = NC_UXX_2Y
  5  VCC  POWER  = P3V3_AUX
  6  \1y\  OUT  = FM_AC_PWR_BTN_PLD_ISO_R_N

U334  74LVC1G08W57  74LVC1G08W5-7 IC  pkg SOT25-5_0-95_3X1-6  page 158
  1  A  IN  = HP_LVC3_OCP_V3_1_PWRGD_R2
  2  B  IN  = OCP_SFF_AUX_PWR_PLD_EN_R
  3  GND  POWER  = GND
  4  Y  OUT  = OCP_SFF_AUX_PWR_EN_R2
  5  VCC  POWER  = P3V3_AUX

U335  74LVC1G08W57  74LVC1G08W5-7 IC  pkg SOT25-5_0-95_3X1-6  page 164
  1  A  IN  = HP_LVC3_OCP_V3_2_PWRGD_R2
  2  B  IN  = OCP_V3_2_AUX_PWR_PLD_EN_R
  3  GND  POWER  = GND
  4  Y  OUT  = OCP_V3_2_AUX_PWR_EN_R2
  5  VCC  POWER  = P3V3_AUX

U336  APX80929SAG7  APX809-29SAG-7 IC  pkg SOT23_123XI  page 191
  1  GND  POWER  = GND
  2  RESET_L  OUT  = HP_E1S_0_P3V3_PWRGD
  3  VCC  POWER  = P3V3_E1S_0

U337  LM4040AIM3X25NOPB  LM4040AIM3X-2.5/NOPB EMPTY  pkg SOT23_123_2-92X1-3  page 307
  1  \1+\  BI  = UV_ADR_P2V5_COMP
  2  \2-\  OUT  = GND
  3  \3\  BI  = NC

U338  LM4040AIM3X25NOPB  LM4040AIM3X-2.5/NOPB EMPTY  pkg SOT23_123_2-92X1-3  page 307
  1  \1+\  BI  = UV_P2V5_COMP
  2  \2-\  OUT  = GND
  3  \3\  BI  = NC

U339  AP331AWG7  AP331AWG-7 EMPTY  pkg SOT25  page 307
  1  \in-\  IN  = UV_ADR_P2V5_COMP
  2  GND  POWER  = GND
  3  \in+\  IN  = P12V_AUX_UV_ADR_TRIGGER
  4  OUTPUT  OUT  = FM_UV_ADR_TRIGGER_N_R2
  5  VCC  POWER  = P12V_AUX

U340  AP331AWG7  AP331AWG-7 EMPTY  pkg SOT25  page 307
  1  \in-\  IN  = UV_P2V5_COMP
  2  GND  POWER  = GND
  3  \in+\  IN  = P12V_AUX_UV_TRIGGER
  4  OUTPUT  OUT  = IRQ_UV_DETECT_R2_N
  5  VCC  POWER  = P12V_AUX

U341  LM4040AIM3X25NOPB  LM4040AIM3X-2.5/NOPB EMPTY  pkg SOT23_123_2-92X1-3  page 307
  1  \1+\  BI  = DSW_PWROK_P2V5_COMP
  2  \2-\  OUT  = GND
  3  \3\  BI  = NC

U342  AP331AWG7  AP331AWG-7 EMPTY  pkg SOT25  page 307
  1  \in-\  IN  = DSW_PWROK_P2V5_COMP
  2  GND  POWER  = GND
  3  \in+\  IN  = PWRGD_DSW_PWROK_TRIGGER
  4  OUTPUT  OUT  = PWRGD_DSW_PWROK_R5
  5  VCC  POWER  = P12V_AUX

U343  LM4040AIM3X25NOPB  LM4040AIM3X-2.5/NOPB EMPTY  pkg SOT23_123_2-92X1-3  page 306
  1  \1+\  BI  = OC_P2V5_COMP
  2  \2-\  OUT  = GND
  3  \3\  BI  = NC

U344  AP331AWG7  AP331AWG-7 EMPTY  pkg SOT25  page 306
  1  \in-\  IN  = OC_P2V5_COMP
  2  GND  POWER  = GND
  3  \in+\  IN  = HSC_OC_VOL
  4  OUTPUT  OUT  = HSC_D_OC_R2
  5  VCC  POWER  = P12V_AUX

U345  NCT7718W  EMPTY  pkg MSOP8_0-65_3X3XE  page 305
  1  VDD  POWER  = P3V3_AUX
  2  \d+\  IN  = P12V_HSC_TEMP_D+
  3  \d-\  IN  = P12V_HSC_TEMP_D-
  4  \t_crit#\  OCA  = P12V_HSC_T_CRIT_N
  5  GND  POWER  = GND
  6  \alert#\  OCA  = P12V_HSC_TEMP_ALERT_N
  7  SDA  BI  = P12V_HSC_TEMP_SDA
  8  SCL  IN  = P12V_HSC_TEMP_SCL

U365  MMBT3904  EMPTY  pkg SMLF  page 305
  B  \1\  IN  = P12V_HSC_TEMP_R
  C  \3\  BI  = P12V_HSC_TEMP_R
  E  \2\  BI  = P12V_HSC_TEMP_E

U369  TPS3700DDCR  EMPTY  pkg SOT23-6XF  page 306
  1  OUTA  OUT  = A_HSC_LOW_GATE
  2  GND  POWER  = GND
  3  \ina+\  IN  = A_HSC_LOW
  4  \inb-\  IN  = A_HSC_HIGH
  5  VDD  POWER  = U369_VDD
  6  OUTB  OUT  = HSC_D_OC

U5201  TUSB211IRWBR  EMPTY  pkg X2QFN12_0-4_1-6X1-6  page 152
  1  D1M  BI  = USB2_HUB_BUF_SWB_R_DN
  2  D1P  BI  = USB2_HUB_BUF_SWB_R_DP
  3  TEST  IN  = TP_USB2_TEST
  4  CD  OUT  = TP_USB2_CD
  5  RSTN  IN  = PD_U5201_RSTN
  6  EQ  IN  = PD_U5201_EQ
  7  D2P  BI  = USB2_HUB_BUF_SWB_R_DP
  8  D2M  BI  = USB2_HUB_BUF_SWB_R_DN
  9  ENA_HS  OUT  = TP_USB2_ENA_HS
  10  GND  POWER  = GND
  11  VREG  OUT  = PD_U5201_VREG
  12  VCC  POWER  = P3V3_AUX

X1  TP_TDR_4P_FTS  TP_TDR_4P_DIP EMPTY  pkg TH  page 309
  1  S1  BI  = TDR_DIFF_85_TOP_DP
  2  P1  BI  = T1_GND
  3  P2  BI  = T1_GND
  4  S2  BI  = TDR_DIFF_85_TOP_DN

X2  TP_TDR_4P_FTS  TP_TDR_4P_DIP EMPTY  pkg TH  page 309
  1  S1  BI  = TDR_DIFF_85_IN1_DP
  2  P1  BI  = T1_GND
  3  P2  BI  = T1_GND
  4  S2  BI  = TDR_DIFF_85_IN1_DN

X3  TP_TDR_4P_FTS  TP_TDR_4P_DIP EMPTY  pkg TH  page 309
  1  S1  BI  = TDR_DIFF_85_IN2_DP
  2  P1  BI  = T1_GND
  3  P2  BI  = T1_GND
  4  S2  BI  = TDR_DIFF_85_IN2_DN
